(kicad_pcb
	(version 20260206)
	(generator "pcbnew")
	(generator_version "10.0")
	(general
		(thickness 1.6)
		(legacy_teardrops no)
	)
	(paper "A4")
	(title_block
		(title "03242023_DA0F0TMBIJ0_F0T_Motherboard_J_brd_V01_OCP.brd")
		(comment 1 "Grand Teton / footprints 4950-4955 of 6105")
	)
	(layers
		(0 "F.Cu" signal "TOP")
		(4 "In1.Cu" signal "GND")
		(6 "In2.Cu" signal "IN1")
		(8 "In3.Cu" signal "GND1")
		(10 "In4.Cu" signal "IN2")
		(12 "In5.Cu" signal "GND2")
		(14 "In6.Cu" signal "IN3")
		(16 "In7.Cu" signal "GND3")
		(18 "In8.Cu" signal "VCC")
		(20 "In9.Cu" signal "VCC1")
		(22 "In10.Cu" signal "GND4")
		(24 "In11.Cu" signal "IN4")
		(26 "In12.Cu" signal "GND5")
		(28 "In13.Cu" signal "IN5")
		(30 "In14.Cu" signal "GND6")
		(32 "In15.Cu" signal "IN6")
		(34 "In16.Cu" signal "GND7")
		(2 "B.Cu" signal "BOTTOM")
		(9 "F.Adhes" user "F.Adhesive")
		(11 "B.Adhes" user "B.Adhesive")
		(13 "F.Paste" user "Package Geometry/Pastemask Top")
		(15 "B.Paste" user "Package Geometry/Pastemask Bottom")
		(5 "F.SilkS" user "Ref Des/Silkscreen Top")
		(7 "B.SilkS" user "Ref Des/Silkscreen Bottom")
		(1 "F.Mask" user "Board Geometry/Soldermask Top")
		(3 "B.Mask" user "Board Geometry/Soldermask Bottom")
		(17 "Dwgs.User" user "User.Drawings")
		(19 "Cmts.User" user "User.Comments")
		(21 "Eco1.User" user "User.Eco1")
		(23 "Eco2.User" user "User.Eco2")
		(25 "Edge.Cuts" user "Board Geometry/Outline")
		(27 "Margin" user)
		(31 "F.CrtYd" user "Package Geometry/Place Bound Top")
		(29 "B.CrtYd" user "Package Geometry/Place Bound Bottom")
		(35 "F.Fab" user "Ref Des/Assembly Top")
		(33 "B.Fab" user "Ref Des/Assembly Bottom")
	)
	(footprint ""
		(layer "B.Cu")
		(at 291.586158 -153.944828)
		(property "Reference" "R692"
			(at 0 0 0)
			(layer "B.SilkS")
			(hide yes)
			(effects
				(font
					(size 1.27 1.27)
				)
				(justify mirror)
			)
		)
		(property "Value" ""
			(at 0 0 0)
			(layer "B.Fab")
			(effects
				(font
					(size 1.27 1.27)
				)
				(justify mirror)
			)
		)
		(duplicate_pad_numbers_are_jumpers no)
		(fp_line
			(start -0.7874 -0.4064)
			(end -0.7874 0.4064)
			(stroke
				(width 0.1524)
				(type default)
			)
			(layer "B.SilkS")
		)
		(fp_line
			(start -0.7874 0.4064)
			(end 0.7874 0.4064)
			(stroke
				(width 0.1524)
				(type default)
			)
			(layer "B.SilkS")
		)
		(fp_line
			(start 0.7874 -0.4064)
			(end -0.7874 -0.4064)
			(stroke
				(width 0.1524)
				(type default)
			)
			(layer "B.SilkS")
		)
		(fp_line
			(start 0.7874 0.4064)
			(end 0.7874 -0.4064)
			(stroke
				(width 0.1524)
				(type default)
			)
			(layer "B.SilkS")
		)
		(fp_line
			(start -0.67945 -0.3048)
			(end -0.67945 0.3048)
			(stroke
				(width 0.1)
				(type default)
			)
			(layer "B.Fab")
		)
		(fp_line
			(start -0.67945 0.3048)
			(end -0.120396 0.3048)
			(stroke
				(width 0.1)
				(type default)
			)
			(layer "B.Fab")
		)
		(fp_line
			(start -0.12065 -0.3048)
			(end -0.67945 -0.3048)
			(stroke
				(width 0.1)
				(type default)
			)
			(layer "B.Fab")
		)
		(fp_line
			(start -0.12065 -0.2794)
			(end -0.12065 -0.3048)
			(stroke
				(width 0.1)
				(type default)
			)
			(layer "B.Fab")
		)
		(fp_line
			(start -0.120396 0.2794)
			(end 0.12065 0.2794)
			(stroke
				(width 0.1)
				(type default)
			)
			(layer "B.Fab")
		)
		(fp_line
			(start -0.120396 0.3048)
			(end -0.120396 0.2794)
			(stroke
				(width 0.1)
				(type default)
			)
			(layer "B.Fab")
		)
		(fp_line
			(start 0.12065 -0.305054)
			(end 0.12065 -0.2794)
			(stroke
				(width 0.1)
				(type default)
			)
			(layer "B.Fab")
		)
		(fp_line
			(start 0.12065 -0.2794)
			(end -0.12065 -0.2794)
			(stroke
				(width 0.1)
				(type default)
			)
			(layer "B.Fab")
		)
		(fp_line
			(start 0.12065 0.2794)
			(end 0.12065 0.3048)
			(stroke
				(width 0.1)
				(type default)
			)
			(layer "B.Fab")
		)
		(fp_line
			(start 0.12065 0.3048)
			(end 0.67945 0.3048)
			(stroke
				(width 0.1)
				(type default)
			)
			(layer "B.Fab")
		)
		(fp_line
			(start 0.67945 -0.305054)
			(end 0.12065 -0.305054)
			(stroke
				(width 0.1)
				(type default)
			)
			(layer "B.Fab")
		)
		(fp_line
			(start 0.67945 0.3048)
			(end 0.67945 -0.305054)
			(stroke
				(width 0.1)
				(type default)
			)
			(layer "B.Fab")
		)
		(pad "1" smd circle
			(at 0.40005 0 180)
			(size 0 0)
			(layers "B.Cu" "B.Mask" "B.Paste")
			(net "I3C_SPD_DDRABCD_CPU0_LVC1_R_SDA")
		)
		(pad "2" smd circle
			(at -0.40005 0 180)
			(size 0 0)
			(layers "B.Cu" "B.Mask" "B.Paste")
			(net "I3C_SPD_DDRABCD_CPU0_LVC1_SDA")
		)
	)
	(footprint ""
		(layer "B.Cu")
		(at 234.230926 -120.851676 180)
		(property "Reference" "R571"
			(at 0 0 0)
			(layer "B.SilkS")
			(hide yes)
			(effects
				(font
					(size 1.27 1.27)
				)
				(justify mirror)
			)
		)
		(property "Value" ""
			(at 0 0 0)
			(layer "B.Fab")
			(effects
				(font
					(size 1.27 1.27)
				)
				(justify mirror)
			)
		)
		(duplicate_pad_numbers_are_jumpers no)
		(fp_line
			(start 1.2954 0.5842)
			(end 1.2954 -0.5842)
			(stroke
				(width 0.1524)
				(type default)
			)
			(layer "B.SilkS")
		)
		(fp_line
			(start 1.2954 -0.5842)
			(end -1.2954 -0.5842)
			(stroke
				(width 0.1524)
				(type default)
			)
			(layer "B.SilkS")
		)
		(fp_line
			(start -1.2954 0.5842)
			(end 1.2954 0.5842)
			(stroke
				(width 0.1524)
				(type default)
			)
			(layer "B.SilkS")
		)
		(fp_line
			(start -1.2954 -0.5842)
			(end -1.2954 0.5842)
			(stroke
				(width 0.1524)
				(type default)
			)
			(layer "B.SilkS")
		)
		(fp_line
			(start 1.1938 0.4064)
			(end 1.1938 -0.406654)
			(stroke
				(width 0.1)
				(type default)
			)
			(layer "B.Fab")
		)
		(fp_line
			(start 1.1938 -0.406654)
			(end 0.8636 -0.406654)
			(stroke
				(width 0.1)
				(type default)
			)
			(layer "B.Fab")
		)
		(fp_line
			(start 0.8636 0.4572)
			(end 0.8636 0.4318)
			(stroke
				(width 0.1)
				(type default)
			)
			(layer "B.Fab")
		)
		(fp_line
			(start 0.8636 0.4318)
			(end 0.8636 0.4064)
			(stroke
				(width 0.1)
				(type default)
			)
			(layer "B.Fab")
		)
		(fp_line
			(start 0.8636 0.4064)
			(end 1.1938 0.4064)
			(stroke
				(width 0.1)
				(type default)
			)
			(layer "B.Fab")
		)
		(fp_line
			(start 0.8636 -0.406654)
			(end 0.8636 -0.4572)
			(stroke
				(width 0.1)
				(type default)
			)
			(layer "B.Fab")
		)
		(fp_line
			(start 0.8636 -0.4572)
			(end -0.8636 -0.4572)
			(stroke
				(width 0.1)
				(type default)
			)
			(layer "B.Fab")
		)
		(fp_line
			(start -0.8636 0.4572)
			(end 0.8636 0.4572)
			(stroke
				(width 0.1)
				(type default)
			)
			(layer "B.Fab")
		)
		(fp_line
			(start -0.8636 0.4064)
			(end -0.8636 0.4572)
			(stroke
				(width 0.1)
				(type default)
			)
			(layer "B.Fab")
		)
		(fp_line
			(start -0.8636 -0.406654)
			(end -1.1938 -0.406654)
			(stroke
				(width 0.1)
				(type default)
			)
			(layer "B.Fab")
		)
		(fp_line
			(start -0.8636 -0.4572)
			(end -0.8636 -0.406654)
			(stroke
				(width 0.1)
				(type default)
			)
			(layer "B.Fab")
		)
		(fp_line
			(start -1.1938 0.4064)
			(end -0.8636 0.4064)
			(stroke
				(width 0.1)
				(type default)
			)
			(layer "B.Fab")
		)
		(fp_line
			(start -1.1938 -0.406654)
			(end -1.1938 0.4064)
			(stroke
				(width 0.1)
				(type default)
			)
			(layer "B.Fab")
		)
		(pad "1" smd rect
			(at 0.7366 0 90)
			(size 0.7112 0.8128)
			(layers "B.Cu" "B.Mask" "B.Paste")
			(net "P3V3_DB2000_FB_VDD")
		)
		(pad "2" smd rect
			(at -0.7366 0 90)
			(size 0.7112 0.8128)
			(layers "B.Cu" "B.Mask" "B.Paste")
			(net "P3V3_DB2000_VDDR")
		)
	)
	(footprint ""
		(layer "B.Cu")
		(at 257.287268 -75.32878 90)
		(property "Reference" "R1650"
			(at 0 0 90)
			(layer "B.SilkS")
			(hide yes)
			(effects
				(font
					(size 1.27 1.27)
				)
				(justify mirror)
			)
		)
		(property "Value" ""
			(at 0 0 90)
			(layer "B.Fab")
			(effects
				(font
					(size 1.27 1.27)
				)
				(justify mirror)
			)
		)
		(duplicate_pad_numbers_are_jumpers no)
		(fp_line
			(start 0.7874 -0.4064)
			(end -0.7874 -0.4064)
			(stroke
				(width 0.1524)
				(type default)
			)
			(layer "B.SilkS")
		)
		(fp_line
			(start -0.7874 -0.4064)
			(end -0.7874 0.4064)
			(stroke
				(width 0.1524)
				(type default)
			)
			(layer "B.SilkS")
		)
		(fp_line
			(start 0.7874 0.4064)
			(end 0.7874 -0.4064)
			(stroke
				(width 0.1524)
				(type default)
			)
			(layer "B.SilkS")
		)
		(fp_line
			(start -0.7874 0.4064)
			(end 0.7874 0.4064)
			(stroke
				(width 0.1524)
				(type default)
			)
			(layer "B.SilkS")
		)
		(fp_line
			(start 0.67945 -0.305054)
			(end 0.12065 -0.305054)
			(stroke
				(width 0.1)
				(type default)
			)
			(layer "B.Fab")
		)
		(fp_line
			(start 0.12065 -0.305054)
			(end 0.12065 -0.2794)
			(stroke
				(width 0.1)
				(type default)
			)
			(layer "B.Fab")
		)
		(fp_line
			(start -0.12065 -0.3048)
			(end -0.67945 -0.3048)
			(stroke
				(width 0.1)
				(type default)
			)
			(layer "B.Fab")
		)
		(fp_line
			(start -0.67945 -0.3048)
			(end -0.67945 0.3048)
			(stroke
				(width 0.1)
				(type default)
			)
			(layer "B.Fab")
		)
		(fp_line
			(start 0.12065 -0.2794)
			(end -0.12065 -0.2794)
			(stroke
				(width 0.1)
				(type default)
			)
			(layer "B.Fab")
		)
		(fp_line
			(start -0.12065 -0.2794)
			(end -0.12065 -0.3048)
			(stroke
				(width 0.1)
				(type default)
			)
			(layer "B.Fab")
		)
		(fp_line
			(start 0.12065 0.2794)
			(end 0.12065 0.3048)
			(stroke
				(width 0.1)
				(type default)
			)
			(layer "B.Fab")
		)
		(fp_line
			(start -0.120396 0.2794)
			(end 0.12065 0.2794)
			(stroke
				(width 0.1)
				(type default)
			)
			(layer "B.Fab")
		)
		(fp_line
			(start 0.67945 0.3048)
			(end 0.67945 -0.305054)
			(stroke
				(width 0.1)
				(type default)
			)
			(layer "B.Fab")
		)
		(fp_line
			(start 0.12065 0.3048)
			(end 0.67945 0.3048)
			(stroke
				(width 0.1)
				(type default)
			)
			(layer "B.Fab")
		)
		(fp_line
			(start -0.120396 0.3048)
			(end -0.120396 0.2794)
			(stroke
				(width 0.1)
				(type default)
			)
			(layer "B.Fab")
		)
		(fp_line
			(start -0.67945 0.3048)
			(end -0.120396 0.3048)
			(stroke
				(width 0.1)
				(type default)
			)
			(layer "B.Fab")
		)
		(pad "1" smd circle
			(at 0.40005 0 270)
			(size 0 0)
			(layers "B.Cu" "B.Mask" "B.Paste")
			(net "PWRGD_P1V05_PCH_AUX_R")
		)
		(pad "2" smd circle
			(at -0.40005 0 270)
			(size 0 0)
			(layers "B.Cu" "B.Mask" "B.Paste")
			(net "PWRGD_P1V05_PCH_AUX")
		)
	)
	(footprint ""
		(layer "B.Cu")
		(at 251.175266 -107.178094)
		(property "Reference" "R1462"
			(at 0 0 0)
			(layer "B.SilkS")
			(hide yes)
			(effects
				(font
					(size 1.27 1.27)
				)
				(justify mirror)
			)
		)
		(property "Value" ""
			(at 0 0 0)
			(layer "B.Fab")
			(effects
				(font
					(size 1.27 1.27)
				)
				(justify mirror)
			)
		)
		(duplicate_pad_numbers_are_jumpers no)
		(fp_line
			(start -0.7874 -0.4064)
			(end -0.7874 0.4064)
			(stroke
				(width 0.1524)
				(type default)
			)
			(layer "B.SilkS")
		)
		(fp_line
			(start -0.7874 0.4064)
			(end 0.7874 0.4064)
			(stroke
				(width 0.1524)
				(type default)
			)
			(layer "B.SilkS")
		)
		(fp_line
			(start 0.7874 -0.4064)
			(end -0.7874 -0.4064)
			(stroke
				(width 0.1524)
				(type default)
			)
			(layer "B.SilkS")
		)
		(fp_line
			(start 0.7874 0.4064)
			(end 0.7874 -0.4064)
			(stroke
				(width 0.1524)
				(type default)
			)
			(layer "B.SilkS")
		)
		(fp_line
			(start -0.67945 -0.3048)
			(end -0.67945 0.3048)
			(stroke
				(width 0.1)
				(type default)
			)
			(layer "B.Fab")
		)
		(fp_line
			(start -0.67945 0.3048)
			(end -0.120396 0.3048)
			(stroke
				(width 0.1)
				(type default)
			)
			(layer "B.Fab")
		)
		(fp_line
			(start -0.12065 -0.3048)
			(end -0.67945 -0.3048)
			(stroke
				(width 0.1)
				(type default)
			)
			(layer "B.Fab")
		)
		(fp_line
			(start -0.12065 -0.2794)
			(end -0.12065 -0.3048)
			(stroke
				(width 0.1)
				(type default)
			)
			(layer "B.Fab")
		)
		(fp_line
			(start -0.120396 0.2794)
			(end 0.12065 0.2794)
			(stroke
				(width 0.1)
				(type default)
			)
			(layer "B.Fab")
		)
		(fp_line
			(start -0.120396 0.3048)
			(end -0.120396 0.2794)
			(stroke
				(width 0.1)
				(type default)
			)
			(layer "B.Fab")
		)
		(fp_line
			(start 0.12065 -0.305054)
			(end 0.12065 -0.2794)
			(stroke
				(width 0.1)
				(type default)
			)
			(layer "B.Fab")
		)
		(fp_line
			(start 0.12065 -0.2794)
			(end -0.12065 -0.2794)
			(stroke
				(width 0.1)
				(type default)
			)
			(layer "B.Fab")
		)
		(fp_line
			(start 0.12065 0.2794)
			(end 0.12065 0.3048)
			(stroke
				(width 0.1)
				(type default)
			)
			(layer "B.Fab")
		)
		(fp_line
			(start 0.12065 0.3048)
			(end 0.67945 0.3048)
			(stroke
				(width 0.1)
				(type default)
			)
			(layer "B.Fab")
		)
		(fp_line
			(start 0.67945 -0.305054)
			(end 0.12065 -0.305054)
			(stroke
				(width 0.1)
				(type default)
			)
			(layer "B.Fab")
		)
		(fp_line
			(start 0.67945 0.3048)
			(end 0.67945 -0.305054)
			(stroke
				(width 0.1)
				(type default)
			)
			(layer "B.Fab")
		)
		(pad "1" smd circle
			(at 0.40005 0 180)
			(size 0 0)
			(layers "B.Cu" "B.Mask" "B.Paste")
			(net "PD_CK440_SBI_CLK")
		)
		(pad "2" smd circle
			(at -0.40005 0 180)
			(size 0 0)
			(layers "B.Cu" "B.Mask" "B.Paste")
			(net "GND")
		)
	)
	(footprint ""
		(layer "B.Cu")
		(at 488.03433 -153.128472 90)
		(property "Reference" "X6"
			(at 1.617218 2.436622 270)
			(unlocked yes)
			(layer "B.SilkS")
			(effects
				(font
					(size 0.7874 0.5842)
					(thickness 0.1524)
				)
				(justify left mirror)
			)
		)
		(property "Value" ""
			(at 0 0 90)
			(layer "B.Fab")
			(effects
				(font
					(size 1.27 1.27)
				)
				(justify mirror)
			)
		)
		(property "Device Type" "TP_TDR_4P_FTS_MPKT4_H025P0200_I"
			(at -1.30175 1.27 0)
			(unlocked yes)
			(layer "B.Fab")
			(hide yes)
			(effects
				(font
					(size 0.635 0.4064)
					(thickness 0.1524)
				)
				(justify mirror)
			)
		)
		(property "User Part Number" "TP15"
			(at -1.30175 1.27 0)
			(unlocked yes)
			(layer "Cmts.User")
			(hide yes)
			(effects
				(font
					(size 0.635 0.4064)
					(thickness 0.1524)
				)
				(justify mirror)
			)
		)
		(duplicate_pad_numbers_are_jumpers no)
		(fp_line
			(start 0 -1.27)
			(end 0 -0.635)
			(stroke
				(width 0.1524)
				(type default)
			)
			(layer "B.SilkS")
		)
		(fp_line
			(start -2.54 -1.27)
			(end 0 -1.27)
			(stroke
				(width 0.1524)
				(type default)
			)
			(layer "B.SilkS")
		)
		(fp_line
			(start -2.54 -1.1303)
			(end -2.54 -1.27)
			(stroke
				(width 0.1524)
				(type default)
			)
			(layer "B.SilkS")
		)
		(fp_line
			(start 0 0.635)
			(end 0 1.905)
			(stroke
				(width 0.1524)
				(type default)
			)
			(layer "B.SilkS")
		)
		(fp_line
			(start -2.54 1.4097)
			(end -2.54 1.1303)
			(stroke
				(width 0.1524)
				(type default)
			)
			(layer "B.SilkS")
		)
		(fp_line
			(start 0 3.175)
			(end 0 3.81)
			(stroke
				(width 0.1524)
				(type default)
			)
			(layer "B.SilkS")
		)
		(fp_line
			(start 0 3.81)
			(end -2.54 3.81)
			(stroke
				(width 0.1524)
				(type default)
			)
			(layer "B.SilkS")
		)
		(fp_line
			(start -2.54 3.81)
			(end -2.54 3.6703)
			(stroke
				(width 0.1524)
				(type default)
			)
			(layer "B.SilkS")
		)
		(fp_poly
			(pts
				(xy 2.790952 -0.930402) (xy 2.790952 0.593598) (xy 1.266952 -0.168402)
			)
			(stroke
				(width 0)
				(type default)
			)
			(fill yes)
			(layer "B.SilkS")
		)
		(fp_line
			(start 0 -1.27)
			(end 0 3.81)
			(stroke
				(width 0.1)
				(type default)
			)
			(layer "B.Fab")
		)
		(fp_line
			(start -2.54 -1.27)
			(end 0 -1.27)
			(stroke
				(width 0.1)
				(type default)
			)
			(layer "B.Fab")
		)
		(fp_line
			(start 0 3.81)
			(end -2.54 3.81)
			(stroke
				(width 0.1)
				(type default)
			)
			(layer "B.Fab")
		)
		(fp_line
			(start -2.54 3.81)
			(end -2.54 -1.27)
			(stroke
				(width 0.1)
				(type default)
			)
			(layer "B.Fab")
		)
		(fp_poly
			(pts
				(xy 0.761746 0) (xy 2.285746 -0.762) (xy 2.285746 0.762)
			)
			(stroke
				(width 0)
				(type default)
			)
			(fill yes)
			(layer "B.Fab")
		)
		(pad "1" thru_hole circle
			(at 0 0 270)
			(size 1.0033 1.0033)
			(drill 0.249936)
			(layers "*.Cu" "*.Mask")
			(remove_unused_layers no)
			(net "TDR_DIFF_85_BOT_DP")
			(clearance 0.10795)
			(padstack
				(mode front_inner_back)
				(layer "Inner"
					(shape circle)
					(size 0.8001 0.8001)
					(clearance 0.1524)
				)
				(layer "B.Cu"
					(shape circle)
					(size 1.0033 1.0033)
					(thermal_gap 0.10795)
					(clearance 0.10795)
				)
			)
		)
		(pad "2" thru_hole circle
			(at -2.54 0 270)
			(size 1.9939 1.9939)
			(drill 0.249936)
			(layers "*.Cu" "*.Mask")
			(remove_unused_layers no)
			(net "T1_GND")
			(clearance 0.10795)
			(padstack
				(mode front_inner_back)
				(layer "Inner"
					(shape circle)
					(size 0.8001 0.8001)
					(clearance 0.1524)
				)
				(layer "B.Cu"
					(shape circle)
					(size 1.9939 1.9939)
					(thermal_gap 0.10795)
					(clearance 0.10795)
				)
			)
		)
		(pad "3" thru_hole circle
			(at -2.54 2.54 270)
			(size 1.9939 1.9939)
			(drill 0.249936)
			(layers "*.Cu" "*.Mask")
			(remove_unused_layers no)
			(net "T1_GND")
			(clearance 0.10795)
			(padstack
				(mode front_inner_back)
				(layer "Inner"
					(shape circle)
					(size 0.8001 0.8001)
					(clearance 0.1524)
				)
				(layer "B.Cu"
					(shape circle)
					(size 1.9939 1.9939)
					(thermal_gap 0.10795)
					(clearance 0.10795)
				)
			)
		)
		(pad "4" thru_hole circle
			(at 0 2.54 270)
			(size 1.0033 1.0033)
			(drill 0.249936)
			(layers "*.Cu" "*.Mask")
			(remove_unused_layers no)
			(net "TDR_DIFF_85_BOT_DN")
			(clearance 0.10795)
			(padstack
				(mode front_inner_back)
				(layer "Inner"
					(shape circle)
					(size 0.8001 0.8001)
					(clearance 0.1524)
				)
				(layer "B.Cu"
					(shape circle)
					(size 1.0033 1.0033)
					(thermal_gap 0.10795)
					(clearance 0.10795)
				)
			)
		)
	)
	(footprint ""
		(layer "B.Cu")
		(at 414.309814 -321.549776 -90)
		(property "Reference" "C28"
			(at 0 0 90)
			(layer "B.SilkS")
			(hide yes)
			(effects
				(font
					(size 1.27 1.27)
				)
				(justify mirror)
			)
		)
		(property "Value" ""
			(at 0 0 90)
			(layer "B.Fab")
			(effects
				(font
					(size 1.27 1.27)
				)
				(justify mirror)
			)
		)
		(duplicate_pad_numbers_are_jumpers no)
		(fp_line
			(start -1.524 0.762)
			(end 1.524 0.762)
			(stroke
				(width 0.1524)
				(type default)
			)
			(layer "B.SilkS")
		)
		(fp_line
			(start 1.524 0.762)
			(end 1.524 -0.762)
			(stroke
				(width 0.1524)
				(type default)
			)
			(layer "B.SilkS")
		)
		(fp_line
			(start -1.524 -0.762)
			(end -1.524 0.762)
			(stroke
				(width 0.1524)
				(type default)
			)
			(layer "B.SilkS")
		)
		(fp_line
			(start 1.524 -0.762)
			(end -1.524 -0.762)
			(stroke
				(width 0.1524)
				(type default)
			)
			(layer "B.SilkS")
		)
		(fp_line
			(start -1.1049 0.724916)
			(end -1.1049 -0.724916)
			(stroke
				(width 0.1)
				(type default)
			)
			(layer "B.Fab")
		)
		(fp_line
			(start 1.1049 0.724916)
			(end -1.1049 0.724916)
			(stroke
				(width 0.1)
				(type default)
			)
			(layer "B.Fab")
		)
		(fp_line
			(start -1.1049 -0.724916)
			(end 1.1049 -0.724916)
			(stroke
				(width 0.1)
				(type default)
			)
			(layer "B.Fab")
		)
		(fp_line
			(start 1.1049 -0.724916)
			(end 1.1049 0.724916)
			(stroke
				(width 0.1)
				(type default)
			)
			(layer "B.Fab")
		)
		(pad "1" smd rect
			(at 0.889 0 270)
			(size 1.016 1.27)
			(layers "B.Cu" "B.Mask" "B.Paste")
			(net "P12V_S3_AUX_CPU0_NVDIMM")
		)
		(pad "2" smd rect
			(at -0.889 0 270)
			(size 1.016 1.27)
			(layers "B.Cu" "B.Mask" "B.Paste")
			(net "GND")
		)
	)
)
